# BARRELEYE_G2-MB-PVT-X04-HW-BOM-X26_20180122_Final.xls.xlsx — DEPOP_GA (bom)
| FOXCONN TECHNOLOGY GROUP |  |  |  |  |  |  |  |  |  |  |  |  |
| BILL OF MATERIAL |  |  |  |  |  |  |  |  |  |  |  |  |
| REV OF  BOM |  | CUSTOMER | RACKSPACE |  | CUSTOMER P/N |  | PRODUCT CODE |  | PWA  REV |  | DATE |  |
| Sourcing (Single/Sole/Multi) | Critical Commodity (Y or N) | Component Class (1, 2, other) | Customer PSL (Y or N) | Item Number | Foxconn P/N | Customer P/N | Part Description | Manufacturer  Full Name | Manufacturer  Part Number | Qty | RoHS Status | Location |
